# T6G (Grand Teton) — schematic netlist excerpt (pin names and nets, part order shuffled) for the footprints in the layout excerpt that follows; sources: Cadence DE-HDL packaged netlist, KiCad conversion of 04192023_DAF0TMB3IC0_F0TG_MB_C_brd_V02_OCP.brd

PR3853  Q_RES  120K 1% CHIP  pkg 0402LF  page 141 : A = P12V_AUX ; B = P12V_OCP_OV_FB_2
R626  Q_RES  51.1 1% EMPTY  pkg 0201LF  page 331 : A = CLK_100M_RETIMER_CPU1_P1_DP ; B = GND
R208  Q_RES  33 5% CHIP  pkg 0402LF  page 81 : A = PVDDCR_CPU0_P1_EN ; B = FM_PVDDCR_CPU0_P1_R_EN

(kicad_pcb
	(version 20260206)
	(generator "pcbnew")
	(generator_version "10.0")
	(general
		(thickness 1.6)
		(legacy_teardrops no)
	)
	(paper "A4")
	(title_block
		(title "04192023_DAF0TMB3IC0_F0TG_MB_C_brd_V02_OCP.brd")
		(comment 1 "Grand Teton / footprints 1636-1638 of 8354")
	)
	(layers
		(0 "F.Cu" signal "TOP")
		(4 "In1.Cu" signal "GND")
		(6 "In2.Cu" signal "IN1")
		(8 "In3.Cu" signal "GND1")
		(10 "In4.Cu" signal "IN2")
		(12 "In5.Cu" signal "GND2")
		(14 "In6.Cu" signal "IN3")
		(16 "In7.Cu" signal "GND3")
		(18 "In8.Cu" signal "VCC")
		(20 "In9.Cu" signal "VCC1")
		(22 "In10.Cu" signal "GND4")
		(24 "In11.Cu" signal "IN4")
		(26 "In12.Cu" signal "GND5")
		(28 "In13.Cu" signal "IN5")
		(30 "In14.Cu" signal "GND6")
		(32 "In15.Cu" signal "IN6")
		(34 "In16.Cu" signal "GND7")
		(2 "B.Cu" signal "BOTTOM")
		(9 "F.Adhes" user "F.Adhesive")
		(11 "B.Adhes" user "B.Adhesive")
		(13 "F.Paste" user "Package Geometry/Pastemask Top")
		(15 "B.Paste" user "Package Geometry/Pastemask Bottom")
		(5 "F.SilkS" user "Ref Des/Silkscreen Top")
		(7 "B.SilkS" user "Ref Des/Silkscreen Bottom")
		(1 "F.Mask" user "Board Geometry/Soldermask Top")
		(3 "B.Mask" user "Board Geometry/Soldermask Bottom")
		(17 "Dwgs.User" user "User.Drawings")
		(19 "Cmts.User" user "User.Comments")
		(21 "Eco1.User" user "User.Eco1")
		(23 "Eco2.User" user "User.Eco2")
		(25 "Edge.Cuts" user "Board Geometry/Outline")
		(27 "Margin" user)
		(31 "F.CrtYd" user "Package Geometry/Place Bound Top")
		(29 "B.CrtYd" user "Package Geometry/Place Bound Bottom")
		(35 "F.Fab" user "Ref Des/Assembly Top")
		(33 "B.Fab" user "Ref Des/Assembly Bottom")
	)
	(footprint ""
		(layer "F.Cu")
		(at 200.939908 -107.529376 180)
		(property "Reference" "R208"
			(at 0 0 180)
			(layer "F.SilkS")
			(hide yes)
			(effects
				(font
					(size 1.27 1.27)
				)
			)
		)
		(property "Value" ""
			(at 0 0 180)
			(layer "F.Fab")
			(effects
				(font
					(size 1.27 1.27)
				)
			)
		)
		(duplicate_pad_numbers_are_jumpers no)
		(fp_line
			(start 0.7874 0.4064)
			(end -0.7874 0.4064)
			(stroke
				(width 0.1524)
				(type default)
			)
			(layer "F.SilkS")
		)
		(fp_line
			(start 0.7874 -0.4064)
			(end 0.7874 0.4064)
			(stroke
				(width 0.1524)
				(type default)
			)
			(layer "F.SilkS")
		)
		(fp_line
			(start -0.7874 0.4064)
			(end -0.7874 -0.4064)
			(stroke
				(width 0.1524)
				(type default)
			)
			(layer "F.SilkS")
		)
		(fp_line
			(start -0.7874 -0.4064)
			(end 0.7874 -0.4064)
			(stroke
				(width 0.1524)
				(type default)
			)
			(layer "F.SilkS")
		)
		(fp_line
			(start 0.67945 0.3048)
			(end 0.120396 0.3048)
			(stroke
				(width 0.1)
				(type default)
			)
			(layer "F.Fab")
		)
		(fp_line
			(start 0.67945 -0.3048)
			(end 0.67945 0.3048)
			(stroke
				(width 0.1)
				(type default)
			)
			(layer "F.Fab")
		)
		(fp_line
			(start 0.12065 -0.2794)
			(end 0.12065 -0.3048)
			(stroke
				(width 0.1)
				(type default)
			)
			(layer "F.Fab")
		)
		(fp_line
			(start 0.12065 -0.3048)
			(end 0.67945 -0.3048)
			(stroke
				(width 0.1)
				(type default)
			)
			(layer "F.Fab")
		)
		(fp_line
			(start 0.120396 0.3048)
			(end 0.120396 0.2794)
			(stroke
				(width 0.1)
				(type default)
			)
			(layer "F.Fab")
		)
		(fp_line
			(start 0.120396 0.2794)
			(end -0.12065 0.2794)
			(stroke
				(width 0.1)
				(type default)
			)
			(layer "F.Fab")
		)
		(fp_line
			(start -0.12065 0.3048)
			(end -0.67945 0.3048)
			(stroke
				(width 0.1)
				(type default)
			)
			(layer "F.Fab")
		)
		(fp_line
			(start -0.12065 0.2794)
			(end -0.12065 0.3048)
			(stroke
				(width 0.1)
				(type default)
			)
			(layer "F.Fab")
		)
		(fp_line
			(start -0.12065 -0.2794)
			(end 0.12065 -0.2794)
			(stroke
				(width 0.1)
				(type default)
			)
			(layer "F.Fab")
		)
		(fp_line
			(start -0.12065 -0.305054)
			(end -0.12065 -0.2794)
			(stroke
				(width 0.1)
				(type default)
			)
			(layer "F.Fab")
		)
		(fp_line
			(start -0.67945 0.3048)
			(end -0.67945 -0.305054)
			(stroke
				(width 0.1)
				(type default)
			)
			(layer "F.Fab")
		)
		(fp_line
			(start -0.67945 -0.305054)
			(end -0.12065 -0.305054)
			(stroke
				(width 0.1)
				(type default)
			)
			(layer "F.Fab")
		)
		(pad "1" smd circle
			(at -0.40005 0 180)
			(size 0 0)
			(layers "F.Cu" "F.Mask" "F.Paste")
			(net "PVDDCR_CPU0_P1_EN")
		)
		(pad "2" smd circle
			(at 0.40005 0 180)
			(size 0 0)
			(layers "F.Cu" "F.Mask" "F.Paste")
			(net "FM_PVDDCR_CPU0_P1_R_EN")
		)
	)
	(footprint ""
		(layer "F.Cu")
		(at 62.861698 -26.99004 90)
		(property "Reference" "PR3853"
			(at 0 0 90)
			(layer "F.SilkS")
			(hide yes)
			(effects
				(font
					(size 1.27 1.27)
				)
			)
		)
		(property "Value" ""
			(at 0 0 90)
			(layer "F.Fab")
			(effects
				(font
					(size 1.27 1.27)
				)
			)
		)
		(duplicate_pad_numbers_are_jumpers no)
		(fp_line
			(start 0.7874 -0.4064)
			(end 0.7874 0.4064)
			(stroke
				(width 0.1524)
				(type default)
			)
			(layer "F.SilkS")
		)
		(fp_line
			(start -0.7874 -0.4064)
			(end 0.7874 -0.4064)
			(stroke
				(width 0.1524)
				(type default)
			)
			(layer "F.SilkS")
		)
		(fp_line
			(start 0.7874 0.4064)
			(end -0.7874 0.4064)
			(stroke
				(width 0.1524)
				(type default)
			)
			(layer "F.SilkS")
		)
		(fp_line
			(start -0.7874 0.4064)
			(end -0.7874 -0.4064)
			(stroke
				(width 0.1524)
				(type default)
			)
			(layer "F.SilkS")
		)
		(fp_line
			(start -0.12065 -0.305054)
			(end -0.12065 -0.2794)
			(stroke
				(width 0.1)
				(type default)
			)
			(layer "F.Fab")
		)
		(fp_line
			(start -0.67945 -0.305054)
			(end -0.12065 -0.305054)
			(stroke
				(width 0.1)
				(type default)
			)
			(layer "F.Fab")
		)
		(fp_line
			(start 0.67945 -0.3048)
			(end 0.67945 0.3048)
			(stroke
				(width 0.1)
				(type default)
			)
			(layer "F.Fab")
		)
		(fp_line
			(start 0.12065 -0.3048)
			(end 0.67945 -0.3048)
			(stroke
				(width 0.1)
				(type default)
			)
			(layer "F.Fab")
		)
		(fp_line
			(start 0.12065 -0.2794)
			(end 0.12065 -0.3048)
			(stroke
				(width 0.1)
				(type default)
			)
			(layer "F.Fab")
		)
		(fp_line
			(start -0.12065 -0.2794)
			(end 0.12065 -0.2794)
			(stroke
				(width 0.1)
				(type default)
			)
			(layer "F.Fab")
		)
		(fp_line
			(start 0.120396 0.2794)
			(end -0.12065 0.2794)
			(stroke
				(width 0.1)
				(type default)
			)
			(layer "F.Fab")
		)
		(fp_line
			(start -0.12065 0.2794)
			(end -0.12065 0.3048)
			(stroke
				(width 0.1)
				(type default)
			)
			(layer "F.Fab")
		)
		(fp_line
			(start 0.67945 0.3048)
			(end 0.120396 0.3048)
			(stroke
				(width 0.1)
				(type default)
			)
			(layer "F.Fab")
		)
		(fp_line
			(start 0.120396 0.3048)
			(end 0.120396 0.2794)
			(stroke
				(width 0.1)
				(type default)
			)
			(layer "F.Fab")
		)
		(fp_line
			(start -0.12065 0.3048)
			(end -0.67945 0.3048)
			(stroke
				(width 0.1)
				(type default)
			)
			(layer "F.Fab")
		)
		(fp_line
			(start -0.67945 0.3048)
			(end -0.67945 -0.305054)
			(stroke
				(width 0.1)
				(type default)
			)
			(layer "F.Fab")
		)
		(pad "1" smd circle
			(at -0.40005 0 90)
			(size 0 0)
			(layers "F.Cu" "F.Mask" "F.Paste")
			(net "P12V_AUX")
		)
		(pad "2" smd circle
			(at 0.40005 0 90)
			(size 0 0)
			(layers "F.Cu" "F.Mask" "F.Paste")
			(net "P12V_OCP_OV_FB_2")
		)
	)
	(footprint ""
		(layer "F.Cu")
		(at 76.07173 -388.030974 90)
		(property "Reference" "R626"
			(at 0 0 90)
			(layer "F.SilkS")
			(hide yes)
			(effects
				(font
					(size 1.27 1.27)
				)
			)
		)
		(property "Value" ""
			(at 0 0 90)
			(layer "F.Fab")
			(effects
				(font
					(size 1.27 1.27)
				)
			)
		)
		(duplicate_pad_numbers_are_jumpers no)
		(fp_line
			(start 0.32512 -0.175006)
			(end 0.32512 0.175006)
			(stroke
				(width 0.1)
				(type default)
			)
			(layer "F.Fab")
		)
		(fp_line
			(start -0.32512 -0.175006)
			(end 0.32512 -0.175006)
			(stroke
				(width 0.1)
				(type default)
			)
			(layer "F.Fab")
		)
		(fp_line
			(start 0.32512 0.175006)
			(end -0.32512 0.175006)
			(stroke
				(width 0.1)
				(type default)
			)
			(layer "F.Fab")
		)
		(fp_line
			(start -0.32512 0.175006)
			(end -0.32512 -0.175006)
			(stroke
				(width 0.1)
				(type default)
			)
			(layer "F.Fab")
		)
		(pad "1" smd rect
			(at -0.2667 0 90)
			(size 0.3048 0.381)
			(layers "F.Cu" "F.Mask" "F.Paste")
			(net "CLK_100M_RETIMER_CPU1_P1_DP")
		)
		(pad "2" smd rect
			(at 0.2667 0 270)
			(size 0.3048 0.381)
			(layers "F.Cu" "F.Mask" "F.Paste")
			(net "GND")
		)
	)
)
